FILE_TYPE = MULTI_PHYS_TABLE;

PART 'FERRITEBEAD'
CLASS=DISCRETE

{========================================================================================}
:CLS_PN          | VALUE      | TOLERANCE    = JEDEC_TYPE          | ALT_SYMBOLS           | DESCRIPTION                                                             | CPN_STATUS ;
{========================================================================================}
 'CL100501A'     | '600OHM'   | '25%'        = 'SMC_0603R'         | '(SMC_0603R)'         | 'FER,600OHM@100MHZ,500MA,0603'                                          | ''        
 'G191-00030-01' | '600OHM'   | '25%'        = 'SMC_0603R'         | '(SMC_0603R)'         | 'FER,600OHM@100MHZ,500MA,0603'                                          | ''        
 'CL100502A'     | '1000OHM'  | '25%'        = 'SMC_0805R'         | '(SMC_0805R)'         | 'FER,1KOHM@100MHZ,25%,200MA,RDC_0.45,0805'                              | ''        
 'CL100503A'     | '30OHM'    | '25%'        = 'SMC_0805R'         | '(SMC_0805R)'         | 'FER,30OHM@100MHZ,25%,3.0A,0805'                                        | ''        
 'CL100505A'     | '330OHM'   | '25%'        = 'SMC_0603R'         | '(SMC_0603R)'         | 'FER,330OHM@100MHZ,1.2A,0603'                                           | ''        
 'CL100506A'     | '220OHM'   | '25%'        = 'SMC_0603R'         | '(SMC_0603R)'         | 'FER,220OHM@100MHZ,450MA,0603'                                          | ''        
 'CL100507A'     | '75OHM'    | '25%'        = 'SMC_0603R'         | '(SMC_0603R)'         | 'FER,75OHM@100MHZ,350MA,0603'                                           | ''        
 'G191-00011-01' | '75OHM'    | '25%'        = 'SMC_0603R'         | '(SMC_0603R)'         | 'FER,75OHM@100MHZ,200MA,0603'                                           | ''        
 'CL100510A'     | '60OHM'    | '25%'        = 'SMC_1210R'         | '(SMC_1210R)'         | 'BEAD, 60OHM@100MHZ, 400MA'                                             | ''        
 'CL100511A'     | '60OHM'    | '25%'        = 'SMC_1210R'         | '(SMC_1210R)'         | 'BEAD, 60OHM@100MHZ, 4.5A'                                              | ''        
 'CL1001324A'    | '100OHM'   | '25%'        = 'SMC_0603R'         | '(SMC_0603R)'         | 'FERRITE, 100OHM, 50MOHM DCR, 2A, 0603'                                 | ''        
 'CL1001382A'    | '220OHM'   | '25%'        = 'SMC_0805R'         | '(SMC_0805R)'         | 'FER, 220OHM, 100MHZ, 2A, 0805'                                         | ''        
 'G191-00027-01' | '220OHM'   | '25%'        = 'SMC_0805R'         | '(SMC_0805R)'         | 'FER, 220OHM, 100MHZ, 2A, 0805'                                         | ''        
 'CL1001432A'    | '50OHM'    | '25%'        = 'SMC_1206R'         | '(SMC_1206R)'         | 'FER, 50OHM, 100MHZ, DCR 0.025OHM, 3A, 1206'                            | ''        
 'CL1001482A'    | '100OHM'   | '25%'        = 'SMC_0805R'         | '(SMC_0805R)'         | 'FER, 100OHM, 25%, 4A, RDC 0.02OHM, 0805'                               | ''        
 'G191-00028-01' | '100OHM'   | '25%'        = 'SMC_0805R'         | '(SMC_0805R)'         | 'FER, 100OHM, 25%, 4A, RDC 0.02OHM, 0805'                               | ''        
 'CL1001400A'    | '220OHM'   | '25%'        = 'SMC_0402R'         | '(SMC_0402R)'         | 'FER, 220OHM+/-25%, 0.35OHM, 300MA, 0402'                               | ''        
 'CL1003593A'    | '220OHM'   | '25%'        = 'SMC_0603R'         | '(SMC_0603R)'         | 'BEAD, 220OHM, +/-25%, 0.040OHM, 2500MA, 0603'                          | ''        
 'G191-00029-01' | '220OHM'   | '25%'        = 'SMC_0603R'         | '(SMC_0603R)'         | 'BEAD, 220OHM, +/-25%, 0.040OHM, 2500MA, 0603'                          | ''        
 'CL1003617A'    | '330OHM'   | '25%'        = 'SMC_0603R'         | '(SMC_0603R)'         | 'FER, 330OHM+/-25%, 100MHZ, 1.5A, RDC 0.08OHM, 0603'                    | ''        
 'G191-00026-01' | '330OHM'   | '25%'        = 'SMC_0603R'         | '(SMC_0603R)'         | 'FER, 330OHM+/-25%, 100MHZ, 1.5A, RDC 0.08OHM, 0603'                    | ''        
 'CL1003681A'    | '1000OHM'  | '25%'        = 'SMC_0402R'         | '(SMC_0402R)'         | 'INDUCTOR, 1000OHM, 25%, 100MHZ, 0402'                                  | ''        
 'CL1003767A'    | '330OHM'   | '25%'        = 'SMC_BD_079X049'    | '(SMC_BD_079X049)'    | 'FER, 330OHM, 100MHZ, 2.5A, 2012, 25%, -55/125C'                        | ''        
 'CL1003783A'    | '80OHM'    | '25%'        = 'SMC_BD_126X063'    | '(SMC_BD_126X063)'    | 'FER, 80OHM, 100MHZ, 25%, 4A, 3216'                                     | ''        
 'CL1003801A'    | '330OHM'   | '25%'        = 'SMC_0805R_H041'    | '(SMC_0805R_H041)'    | 'FER, 330OHM, 25%, 100MHZ, 1.5A, 0805'                                  | ''        
 'G191-00015-01' | '330OHM'   | '25%'        = 'SMC_L_0805'        | '(SMC_L_0805)'        | 'FER,330OHM@100MHZ,2500MA,0805'                                         | ''        
 'G191-00017-01' | '100OHM'   | '25%'        = 'SMC_L_0805'        | '(SMC_L_0805)'        | 'FER,100OHM@100MHZ,25%,4A,0805'                                         | ''        
 'G191-00020-01' | '120OHM'   | '25%'        = 'SMC_0603R'         | '(SMC_0603R)'         | 'FER,120OHM@100MHZ,2A,0603'                                             | ''        
 'G191-10011-01' | '470OHM'   | '25%'        = 'SMC_0603R_H037'    | '(SMC_0603R_H037)'    | 'FER,470OHM@100MHZ,1000MA,0603'                                         | ''        
 'G191-10021-01' | '220OHM'   | '25%'        = 'SMC_0603R_H037'    | '(SMC_0603R_H037)'    | 'FER,TSB,220 OHM@100MHZ,25%,2A,0.05OHM,0603,SMT'                        | ''        
 'G191-10027-01' | '42OHM'    | '25%'        = 'SMC_L_160X120'     | '(SMC_L_160X120)'     | 'FER,42OHM@10MHZ,0.00075,10A,4.06X3.05X2.54MM'                          | ''        
 'G191-10044-01' | '600OHM'   | '25%'        = 'SMC_L_0805'        | '(SMC_L_0805)'        | 'FER,600OHM@100MHZ,1500MA,0805'                                         | ''        
 'G191-10000-01' | '600OHM'   | '25%'        = 'SMC_L_0603'        | '(SMC_L_0603)'        | 'FER,600OHM@100MHZ,1.0A,0603'                                           | ''        
 'G191-10052-01' | '800OHM'   | '25%'        = 'SMC_2220R_V2_H152' | '(SMC_2220R_V2_H152)' | 'FER,800OHM@100MHZ,8000MA,2220'                                         | ''        
 'G191-00013-01' | '30OHM'    | '25%'        = 'SMC_L_0603'        | '(SMC_L_0603)'        | 'FER,30OHM@100MHZ,5000MA,0603'                                          | ''        
 'G191-10057-01' | '600OHM'   | '30%'        = 'SMC_1210R_H110'    | '(SMC_1210R_H110)'    | 'FER,600OHM@100MHZ,3A,1210'                                             | ''        
 'G191-10051-01' | '120OHM'   | '25%'        = 'SMC_L_0603_H026'   | '(SMC_L_0603_H026)'   | 'FER,120OHM@100MHZ,3A,0603'                                             | ''        
 'G191-10035-01' | '600OHM'   | '25%'        = 'SMC_L_0805'        | '(SMC_L_0805)'        | 'FER,600OHM@100MHZ,2A,0805'                                             | ''        
 'G191-00024-01' | '220OHM'   | '25%'        = 'SMC_L_0805'        | '(SMC_L_0805)'        | 'FER,220OHM@100MHZ,0.04OHM,3000MA,0805'                                 | ''        
 'G191-10045-01' | '600OHM'   | '25%'        = 'SMC_L_0603_H030'   | '(SMC_L_0603_H030)'   | 'FER,600OHM@100MHZ,1300MA,0603'                                         | ''        
 'G191-10058-01' | '220OHM'   | '30%'        = 'SMC_1206R_H071'    | '(SMC_1206R_H071)'    | 'BEAD,220OHM,+/-30%,0.020OHM,4000MA,1206'                               | ''        
 'G191-10043-01' | '100OHM'   | '25%'        = 'SMC_2220R_V2'      | '(SMC_2220R_V2)'      | 'FER,100OHM@100MHZ,0.006OHM DCR,6A,2220'                                | ''        
 'G191-10060-01' | '26OHM'    | '25%'        = 'SMC_L_0603_H030'   | '(SMC_L_0603_H030)'   | 'FER,26OHM@100MHZ,6A,0603'                                              | ''        
 'G191-10047-01' | '120OHM'   | '25%'        = 'SMC_L_0603'        | '(SMC_L_0603)'        | 'FER,120OHM@100MHZ,2000MA,0603'                                         | ''        
 'G191-10014-01' | '300OHM'   | '25%'        = 'SMC_L_0603'        | '(SMC_L_0603)'        | 'FER,300OHM/100MHZ,500MA,0603'                                          | ''        
 'G191-10062-01' | '1000OHM'  | '25%'        = 'SMC_L_0402'        | '(SMC_L_0402)'        | 'FER,1000OHM@100MHZ,1400OHM@1GHZ,1.1OHM DCR,250MA,-55 C TO +125 C,0402' | ''        
 'G191-10038-01' | '220OHM'   | '25%'        = 'SMC_L_0603'        | '(SMC_L_0603)'        | 'FER,220OHM@100MHZ,2A,0603'                                             | ''        
 'G191-10041-01' | '115OHM'   | '25%'        = 'SMC_L_335X180'     | '(SMC_L_335X180)'     | 'FER,115OHM@100MHZ,10A,3618'                                            | ''        
 'G191-10063-01' | '1KOHM'    | '25%'        = 'SMC_L_177X063'     | '(SMC_L_177X063)'     | 'FER,1KOHM@100MHZ,1.5A,4.5MMX1.6MM,SMT'                                 | ''        
 'G191-00021-01' | '60OHM'    | '25%'        = 'SMC_0805R'         | '(SMC_0805R)'         | 'FER,60OHM@100MHZ,3000MA,0805'                                          | ''        
 'G191-10064-01' | '600OHM'   | '25%'        = 'SMC_2220R_V2_H130' | '(SMC_2220R_V2_H130)' | 'FER,600OHM@100MHZ,4000MA,0.025OHM,2220'                                | ''        
 'G191-10036-01' | '30OHM'    | '25%'        = 'SMC_L_0805'        | '(SMC_L_0805)'        | 'FER,30OHM@100MHZ,+/-10OHM,6.0A,0805'                                   | ''        
 'G191-10029-01' | '300OHM'   | '25%'        = 'SMC_L_0603'        | '(SMC_L_0603)'        | 'FER,300OHM/100MHZ,25%,2A,0.1OHM,0603'                                  | ''        
 'G191-10012-01' | '100OHM'   | '25%'        = 'SMC_L_0603'        | '(SMC_L_0603)'        | 'FER,100OHM@100MHZ,500MA,0603'                                          | ''        
 'G191-10013-01' | '80OHM'    | '25%'        = 'SMC_L_0805'        | '(SMC_L_0805)'        | 'FER,80OHM@100MHZ,500MA,0805'                                           | ''        
 'G191-10025-01' | '330OHM'   | '25%'        = 'SMC_0603R_H037'    | '(SMC_0603R_H037)'    | 'FER,330OHM/100MHZ,25%,1A,0.2OHM,0603'                                  | ''        
 'G191-10065-01' | '1500OHM'  | '25%'        = 'SMC_L_0603'        | '(SMC_L_0603)'        | 'FER,1500OHM@100MHZ,500MA,0603'                                         | ''        
 'G191-10066-01' | '600OHM'   | '25%'        = 'SMC_0603R_H037'    | '(SMC_0603R_H037)'    | 'FER,600OHM@100MHZ,25%,400MA,0.3OHM,0603'                               | ''    
 'G191-10002-01' | '30OHM'    | '25%'        = 'SMC_0603R'         | '(SMC_0603R)'         | 'FER,30 OHM@100MHZ,25%,1A,15MOHM,G,0603'                                | ''        
 'G191-10067-01' | '600OHM'   | '25%'        = 'SMC_L_0402_H024'   | '(SMC_L_0402_H024)'   | 'FER,600OHM@100MHZ,300MA,0402'                                          | ''        
 'G191-00014-01' | '600OHM'   | '25%'        = 'SMC_L_0603'        | '(SMC_L_0603)'        | 'FER,600OHM@100MHZ,500MA,0603'                                          | ''        
 'G191-00009-01' | '330OHM'   | '25%'        = 'SMC_L_0603'        | '(SMC_L_0603)'        | 'FER,330OHM@100MHZ,1.2A,0603'                                           | ''        
 'G191-10069-01' | '120OHM'   | '30%'        = 'SMC_L_079X063_V4'  | '(SMC_L_079X063_V4)'  | 'FER,120OHM@100MHZ,30%,4.5A,0.015OHM,0806'                              | ''        
 'G191-00022-01' | '600OHM'   | '25%'        = 'SMC_1206R_H051'    | '(SMC_1206R_H051)'    | 'FER,600OHM@100MHZ,1500MA,1206'                                         | ''        
 'G191-10070-01' | '30OHM'    | 'NA'         = 'SMC_1210R_H087'    | '(SMC_1210R_H087)'    | 'FER,30OHM@100MHZ,10A,1210'                                             | ''        
 'G191-10071-01' | '920OHM'   | 'NA'         = 'R2_L236_P157'      | '(R2_L236_P157)'      | 'FER,920OHM@25MHZ,3A,WIRE LEAD,DIP'                                     | ''        
 'G191-10072-01' | '30OHM'    | 'NA'         = 'SMC_0805R_H041'    | '(SMC_0805R_H041)'    | 'FER,30OHM@100MHZ,,6.0A,0805'                                           | ''        
 'G191-10073-01' | '60OHM'    | 'NA'         = 'SMC_0603R_H030'    | '(SMC_0603R_H030)'    | 'BEAD, 60OHM@100MHZ, 3.5A, 0.02OHM,SMD0603'                             | ''        
 'G191-10074-01' | '330OHM'   | '25%'        = 'SMC_0603R_H037'    | '(SMC_0603R_H037)'    | 'FER, 330OHM@100MHZ,1.7A, RDC 0.08OHM,25% 0603'                         | ''        
 'G191-10075-01' | '80OHM'    | 'NA'         = 'SMC_0805R_H041'    | '(SMC_0805R_H041)'    | 'FER,80OHM@100MHZ,800MA,0805'                                           | ''        
 'G191-10076-01' | '120OHM'   | 'NA'         = 'SMC_0603R_H030'    | '(SMC_0603R_H030)'    | 'FER,120OHM@100MHZ,3A,0603'                                             | 'NFND'        
 'A191-00003-AW' | '220OHM'   | '25%'        = 'SMC_L_0603_H026'   | '(SMC_L_0603_H026)'   | 'FER,220OHM@100MHZ,25%,2.5A@85C,1.0A@125C,RDC 0.04OHM,0603'             | ''        
 'A191-00002-AW' | '600OHM'   | '25%'        = 'SMC_L_0603'        | '(SMC_L_0603)'        | 'FER,600OHM@100MHZ,25%,1.0A,RDC 0.15OHM,0603'                           | ''        
 'A191-00001-AW' | '330OHM'   | '25%'        = 'SMC_L_0805'        | '(SMC_L_0805)'        | 'FER,330OHM@100MHZ,25%,2.8A@85C,1.9A@125C,RDC 0.04OHM,0805'             | ''        
 'G191-10077-01' | '96OHM'    | 'NA'         = 'SMC_L_335X120'     | '(SMC_L_335X120)'     | 'FER,96 OHM@100MHZ,10A,3312'                                            | ''        
 'G191-10078-01' | '180OHM'   | 'NA'         = 'SMC_L_0603'        | '(SMC_L_0603)'        | 'FER,180 OHM@100MHZ,1.5A,0603'                                          | ''        
 'G191-10079-01' | '1000OHM'  | 'NA'         = 'SMC_0402R_H028'    | '(SMC_0402R_C_H028)'  | 'FER,1000OHM@100MHZ,0.2A,0402'                                          | ''        
 'G191-10006-01' | '330OHM'   | '25%'        = 'SMC_L_0805'        | '(SMC_L_0805)'        | 'FER,330 OHM@100MHZ,25%,1.8A,80MOHM,0805'                               | ''        
 'G191-10010-01' | '600OHM'   | '25%'        = 'SMC_0603R_H037'    | '(SMC_0603R_H037)'    | 'FER,600OHM@100MHZ,500MA,25%,350MOHM,0603'                              | ''        
 'G191-10084-01' | '600OHM'   | '25%'        = 'SMC_0603R_H037'    | '(SMC_0603R_H037)'    | 'FER,600 OHM@100MHZ,0.7A,0603'                                          | ''        
 'G191-10085-01' | '120OHM'   | 'NA'         = 'SMC_L_126X063'     | '(SMC_L_126X063)'     | 'FER,120 OHM@100MHZ,4A,3.2MM*1.6MM'                                     | ''        
 'G191-10086-01' | '120OHM'   | '25%'        = 'SMC_L_0603'        | '(SMC_L_0603)'        | 'FER,120OHM@100MHZ,0.55A,0603'                                          | ''        
 'G191-10087-01' | '33OHM'    | '25%'        = 'SMC_L_0603'        | '(SMC_L_0603)'        | 'FER,33OHM@100MHZ,6000MA,0603'                                          | ''        
 'G191-10088-01' | '120OHM'   | '25%'        = 'SMC_L_0402_H024'   | '(SMC_L_0402_H024)'   | 'FER,120OHM@100MHZ,300MA,0402'                                          | ''        
 'G191-10080-01' | '120OHM'   | '25%'        = 'SMC_0402R_H024'    | '(SMC_0402R_C_H024)'  | 'FER,120 OHM@100MHZ,1.3A,0402'                                          | ''        
 'A191-00001-FB' | '600OHM'   | '25%'        = 'SMC_1206R_H071'    | '(SMC_1206R_H071)'    | 'FER,600OHM/25%@100MHZ,2.9A,0.038OHM,1206'                              | ''        
 'A191-00002-FB' | '470OHM'   | '25%'        = 'SMC_1206R_H071'    | '(SMC_1206R_H071)'    | 'FER,470OHM/25%@100MHZ,4.0A,0.02OHM,1206'                               | ''        
 'P191-00026-01' | '330OHM'   | '25%'        = 'SMC_0603R_H037'    | '(SMC_0603R_H037)'    | 'FER,330OHM@100MHZ,RDC 0.08OHM,25%,1.5A,0603'                           | ''        
 'P191-10072-01' | '30OHM'    | 'NA'         = 'SMC_0805R_H043'    | '(SMC_0805R_H043)'    | 'FER,30OHM@100MHZ,,6.0A,0805,HEIGHT 0.9MM'                              | ''        
 'G191-10081-01' | '10OHM'    | '25%'        = 'SMC_0402R_H024'    | '(SMC_0402R_C_H024)'  | 'FER,10 OHM@100MHZ,1000MA,0402'                                         | ''        
 'G191-10082-01' | '70OHM'    | '25%'        = 'SMC_0603R_H037'    | '(SMC_0603R_H037)'    | 'FER,70 OHM@100MHZ,4.0A,0603'                                           | ''        
 'P191-00029-01' | '0.040OHM' | '25%'        = 'SMC_0603R_H026'    | '(SMC_0603R_H026)'    | 'FER,0.040OHM,220OHM,+/-25%,100MHZ,2500MA,0603'                         | ''        
 'A191-10000-FB' | '600OHM'   | '25%'        = 'SMC_L_0603'        | '(SMC_L_0603)'        | 'FER,600OHM@100MHZ,1.0A,0.15OHM-DCR,0603'                               | ''        
 'A191-10051-FB' | '120OHM'   | '25%'        = 'SMC_0603R_H030'    | '(SMC_0603R_H030)'    | 'FER,120OHM@100MHZ,3A,0.03OHM-DCR,0603,HEIGHT 0.6MM'                    | ''        
 'P191-10051-01' | '120OHM'   | '25%'        = 'SMC_L_0603_H026'   | '(SMC_L_0603_H026)'   | 'FER,120OHM@100MHZ,3A,0603'                                             | ''        
 'P191-10038-01' | '220OHM'   | '25%'        = 'SMC_0603R_H037'    | '(SMC_0603R_H037)'    | 'FER,220OHM@100MHZ,2A,100MOHM,0603'                                     | ''        
 'P191-00020-01' | '120OHM'   | '25%'        = 'SMC_0603R'         | '(SMC_0603R)'         | 'FER,120OHM@100MHZ,2A,0.08OHM,1.6*0.8*0.8MM'                            | ''        
 'G191-10026-01' | '33OHM'    | '25%'        = 'SMC_0603R_H037'    | '(SMC_0603R_H037)'    | 'FER,33OHM/100MHZ,25%,3A,0.04OHM,0603'                                  | ''        
 'A191-10084-AL' | '470OHM'   | '25%'        = 'SMC_1206R_H071'    | '(SMC_1206R_H071)'    | 'FER,470OHM/25%@100MHZ,4.0A,0.02OHM,1206'                               | ''
 'G191-10089-01' | '100OHM'   | '30%'        = 'SMC_0603R_H037'    | '(SMC_0603R_H037)'    | 'FER,100OHM@100MHZ,3A,RDC 0.04OHM,0603'                                 | ''
 'G191-10090-01' | '600OHM'   | '25%'        = 'SMC_0603R_H037'    | '(SMC_0603R_H037)'    | 'FER,600OHM@100MHZ,2A,0.1OHM,0603'                                      | ''
 'A191-00016-FB' | '1000OHM'  | 'NA'         = 'SMC_0402R_H022'    | '(SMC_0402R_C_H022)'  | 'FER,1000OHM@100MHZ,1400OHM@1GHZ,1OHM DCR,250MA,-55 C TO +125 C,0402'   | ''
 'A191-00029-FB' | '220OHM'   | '25%'        = 'SMC_0603R_H026'    | '(SMC_0603R_H026)'    | 'BEAD,220OHM@100MHZ,+/-25%,0.040OHM,2500MA,0603'                        | ''   
 'A191-00026-FB' | '330OHM'   | '25%'        = 'SMC_0603R_H037'    | '(SMC_0603R_H037)'    | 'FER,330OHM+25%@100MHZ,1.5A,0603'                                       | '' 
 'G191-10040-01' | '1000OHM'  | '25%'        = 'SMC_L_0603'        | '(SMC_L_0603)'        | 'FER,1000OHM@100MHZ,600MA,0603'                                         | ''   
 'G191-00008-01' | '1KOHM'    | '25%'        = 'SMC_0805R_H041'    | '(SMC_0805R_H041)'    | 'FER,1KOHM@100MHZ,25%,500MA,RDC_0.3,0805'                               | ''     
 'G191-00019-01' | '1KOHM'    | '25%'        = 'SMC_0402R_H022'    | '(SMC_0402R_C_H022)'  | 'FER,1KOHM@100MHZ,200MA,0402'                                           | ''    
 'A191-10082-AL' | '70OHM'    | '25%'        = 'SMC_0603R_H026'    | '(SMC_0603R_H026)'    | 'FER,70 OHM@100MHZ,4.0A,0603,T0.8MM'                                    | ''    
 'A191-10085-AL' | '600OHM'   | '25%'        = 'SMC_1206R_H071'    | '(SMC_1206R_H071)'    | 'FER,600OHM/25%@100MHZ,2.9A,0.038OHM,1206'                              | ''
 'G191-10091-01' | '100OHM'   | '25%'        = 'SMC_0603R_H030'    | '(SMC_0603R_H030)'    | 'FER,100OHM@100MHZ,3A,RDC 0.03OHM,0603'                                 | ''
 'G191-10092-01' | '50OHM'    | '25%'        = 'SMC_1206R_H051'    | '(SMC_1206R_H051)'    | 'FER,50 OHM@100MHZ,12A,1206'                                            | ''
 'A191-10012-FB' | '100OHM'   | '25%'        = 'SMC_0603R_H037'    | '(SMC_0603R_H037)'    | 'FER,100OHM@100MHZ,500MA,0603'                                          | ''
 'G191-10093-01' | '220OHM'   | '25%'        = 'SMC_0402R_H022'    | '(SMC_0402R_C_H022)'  | 'FER,220OHM/100MHZ,+/-25%,1.4A,0402'                                    | ''
 'G191-10095-01' | '600OHM'   | '25%'        = 'SMC_0603R_H037'    | '(SMC_0603R_H037)'    | 'FER,600 OHM@100MHZ,2A,0603'                                            | ''
 'G191-10096-01' | '600OHM'   | '25%'        = 'SMC_0603R_H037'    | '(SMC_0603R_H037)'    | 'FER,600OHM@100MHZ,2A,0603'                                             | ''
 'A191-00014-IB' | '600OHM'   | '25%'        = 'SMC_L_0603'        | '(SMC_L_0603)'        | 'FER,600OHM@100MHZ,0.5A,DCR=0.48OHM,0603'                               | ''        
 'A191-10000-IB' | '600OHM'   | '25%'        = 'SMC_L_0603'        | '(SMC_L_0603)'        | 'FER,600OHM@100MHZ,1.0A,DCR=0.165 OHM,0603'                             | ''        
 'A191-10029-IB' | '300OHM'   | '25%'        = 'SMC_L_0603'        | '(SMC_L_0603)'        | 'FER,300OHM@100MHZ,2.0A,DCR=0.1 OHM,0603'                               | ''        
 'A191-10043-IB' | '100OHM'   | '25%'        = 'SMC_2220R_V2'      | '(SMC_2220R_V2)'      | 'FER,100OHM@100MHZ,6.0A,DCR-6MOHM,2220'                                 | ''        
 'A191-10016-IB' | '600OHM'   | '25%'        = 'SMC_L_0603'        | '(SMC_L_0603)'        | 'FER,600OHM@100MHZ,0.5A,0603'                                           | ''        
 'G191-10097-01' | '600OHM'   | '25%'        = 'SMC_0603R_H037'    | '(SMC_0603R_H037)'    | 'FER,600OHM@100MHZ,1.3A,150MOHM,0603'                                   | 'PREFER'
 'G191-10098-01' | '330OHM'   | '25%'        = 'SMC_0603R_H037'    | '(SMC_0603R_H037)'    | 'FER,330OHM@100MHZ,1.7A,80MOHM,0603'                                    | 'PREFER'
 'G191-10099-01' | '220OHM'   | '25%'        = 'SMC_0603R_H037'    | '(SMC_0603R_H037)'    | 'FER,220OHM@100MHZ,2.2A,50MOHM,0603'                                    | 'PREFER'
 'G191-10100-01' | '120OHM'   | '25%'        = 'SMC_0603R_H030'    | '(SMC_0603R_H030)'    | 'FER,120OHM@100MHZ,3A,30MOHM,0603'                                      | 'PREFER'
 'G191-10101-01' | '26OHM'    | '25%'        = 'SMC_0603R_H030'    | '(SMC_0603R_H030)'    | 'FER,26OHM@100MHZ,6A,7MOHM,0603'                                        | 'PREFER'
 'G191-00014-02' | '600OHM'   | '25%'        = 'SMC_L_0603'        | '(SMC_L_0603)'        | 'FER,600OHM@100MHZ,0.5A,DCR=0.48OHM,0603'                               | ''        
 'G191-10000-02' | '600OHM'   | '25%'        = 'SMC_L_0603'        | '(SMC_L_0603)'        | 'FER,600OHM@100MHZ,1.0A,DCR=0.165 OHM,0603'                             | ''        
 'G191-10029-02' | '300OHM'   | '25%'        = 'SMC_L_0603'        | '(SMC_L_0603)'        | 'FER,300OHM@100MHZ,2.0A,DCR=0.1 OHM,0603'                               | ''        
 'G191-10043-02' | '100OHM'   | '25%'        = 'SMC_2220R_V2'      | '(SMC_2220R_V2)'      | 'FER,100OHM@100MHZ,6.0A,DCR-6MOHM,2220'                                 | ''        
 'G191-00017-02' | '100OHM'   | '25%'        = 'SMC_L_0805_H043'   | '(SMC_L_0805_H043)'   | 'FER,100OHM@100MHZ,25%,RDC 0.02OHM,4A,0805'                             | ''        
 'G191-00027-02' | '220OHM'   | '25%'        = 'SMC_0805R_H041'    | '(SMC_0805R_H041)'    | 'FER,220OHM@100MHZ,2A,DCR=45MOHM,0805'                                  | ''        
 'G191-00020-02' | '120OHM'   | '25%'        = 'SMC_0603R_H037'    | '(SMC_0603R_H037)'    | 'FER,120OHM@100MHZ,2A,0603'                                             | ''        
 'G191-10070-02' | '30OHM'    | 'NA'         = 'SMC_1210R_H087'    | '(SMC_1210R_H087)'    | 'FER,30OHM@100MHZ,10A,DCR 0.0021OHM,1210'                               | ''        
 'G191-10047-02' | '120OHM'   | '25%'        = 'SMC_0603R_H037'    | '(SMC_0603R_H037)'    | 'FER,120OHM@100MHZ,2000MA,DCR 0.06OHM,0603'                             | ''        
 'A191-00001-IN' | '50OHM'    | 'NA'         = 'SMC_1206R_H051'    | '(SMC_1206R_H051)'    | 'FER,50 OHM@100MHZ,12A,1206,AUTOMOTIVE ELECTRONICS'                     | ''        
 'G191-10012-02' | '100OHM'   | '25%'        = 'SMC_0603R_H037'    | '(SMC_0603R_H037)'    | 'FER,100OHM@100MHZ,500MA,DCR 0.25OHM,-40~125C,0603'                     | ''
 'A191-00020-HT' | '120OHM'   | 'NA'         = 'SMC_0603R_H037'    | '(SMC_0603R_H037)'    | 'FER,120OHM@100MHZ,2A,DCR 0.05OHM,1.6X0.8X0.8MM'                        | ''
 'A191-00014-HT' | '600OHM'   | 'NA'         = 'SMC_0603R_H037'    | '(SMC_0603R_H037)'    | 'FER,600OHM@100MHZ,DCR 0.4OHM,500MA,0603'                               | ''

END_PART

END.

